# T6G (Grand Teton) — schematic netlist excerpt (pin names and nets, part order shuffled) for the footprints in the layout excerpt that follows; sources: Cadence DE-HDL packaged netlist, KiCad conversion of 04192023_DAF0TMB3IC0_F0TG_MB_C_brd_V02_OCP.brd

R1655  Q_RES  1K 1% EMPTY  pkg 0402LF  page 77 : A = P3V3_AUX ; B = SPI_CPU0_LVC3_SCM_CS1_N
C1070  Q_CAP  0.1UF 10V 10% X7S  pkg C0201  page 186 : A = P3V3_AUX ; B = GND
R239  Q_RES  0 5% CHIP  pkg 0402LF  page 82 : A = CPU0_XTRIG_L7 ; B = FM_CPU0_XTRIG_L7

(kicad_pcb
	(version 20260206)
	(generator "pcbnew")
	(generator_version "10.0")
	(general
		(thickness 1.6)
		(legacy_teardrops no)
	)
	(paper "A4")
	(title_block
		(title "04192023_DAF0TMB3IC0_F0TG_MB_C_brd_V02_OCP.brd")
		(comment 1 "Grand Teton / footprints 3028-3030 of 8354")
	)
	(layers
		(0 "F.Cu" signal "TOP")
		(4 "In1.Cu" signal "GND")
		(6 "In2.Cu" signal "IN1")
		(8 "In3.Cu" signal "GND1")
		(10 "In4.Cu" signal "IN2")
		(12 "In5.Cu" signal "GND2")
		(14 "In6.Cu" signal "IN3")
		(16 "In7.Cu" signal "GND3")
		(18 "In8.Cu" signal "VCC")
		(20 "In9.Cu" signal "VCC1")
		(22 "In10.Cu" signal "GND4")
		(24 "In11.Cu" signal "IN4")
		(26 "In12.Cu" signal "GND5")
		(28 "In13.Cu" signal "IN5")
		(30 "In14.Cu" signal "GND6")
		(32 "In15.Cu" signal "IN6")
		(34 "In16.Cu" signal "GND7")
		(2 "B.Cu" signal "BOTTOM")
		(9 "F.Adhes" user "F.Adhesive")
		(11 "B.Adhes" user "B.Adhesive")
		(13 "F.Paste" user "Package Geometry/Pastemask Top")
		(15 "B.Paste" user "Package Geometry/Pastemask Bottom")
		(5 "F.SilkS" user "Ref Des/Silkscreen Top")
		(7 "B.SilkS" user "Ref Des/Silkscreen Bottom")
		(1 "F.Mask" user "Board Geometry/Soldermask Top")
		(3 "B.Mask" user "Board Geometry/Soldermask Bottom")
		(17 "Dwgs.User" user "User.Drawings")
		(19 "Cmts.User" user "User.Comments")
		(21 "Eco1.User" user "User.Eco1")
		(23 "Eco2.User" user "User.Eco2")
		(25 "Edge.Cuts" user "Board Geometry/Outline")
		(27 "Margin" user)
		(31 "F.CrtYd" user "Package Geometry/Place Bound Top")
		(29 "B.CrtYd" user "Package Geometry/Place Bound Bottom")
		(35 "F.Fab" user "Ref Des/Assembly Top")
		(33 "B.Fab" user "Ref Des/Assembly Bottom")
	)
	(footprint ""
		(layer "F.Cu")
		(at 177.8762 -96.103948 90)
		(property "Reference" "R239"
			(at 0 0 90)
			(layer "F.SilkS")
			(hide yes)
			(effects
				(font
					(size 1.27 1.27)
				)
			)
		)
		(property "Value" ""
			(at 0 0 90)
			(layer "F.Fab")
			(effects
				(font
					(size 1.27 1.27)
				)
			)
		)
		(duplicate_pad_numbers_are_jumpers no)
		(fp_line
			(start 0.7874 -0.4064)
			(end 0.7874 0.4064)
			(stroke
				(width 0.1524)
				(type default)
			)
			(layer "F.SilkS")
		)
		(fp_line
			(start -0.7874 -0.4064)
			(end 0.7874 -0.4064)
			(stroke
				(width 0.1524)
				(type default)
			)
			(layer "F.SilkS")
		)
		(fp_line
			(start 0.7874 0.4064)
			(end -0.7874 0.4064)
			(stroke
				(width 0.1524)
				(type default)
			)
			(layer "F.SilkS")
		)
		(fp_line
			(start -0.7874 0.4064)
			(end -0.7874 -0.4064)
			(stroke
				(width 0.1524)
				(type default)
			)
			(layer "F.SilkS")
		)
		(fp_line
			(start -0.12065 -0.305054)
			(end -0.12065 -0.2794)
			(stroke
				(width 0.1)
				(type default)
			)
			(layer "F.Fab")
		)
		(fp_line
			(start -0.67945 -0.305054)
			(end -0.12065 -0.305054)
			(stroke
				(width 0.1)
				(type default)
			)
			(layer "F.Fab")
		)
		(fp_line
			(start 0.67945 -0.3048)
			(end 0.67945 0.3048)
			(stroke
				(width 0.1)
				(type default)
			)
			(layer "F.Fab")
		)
		(fp_line
			(start 0.12065 -0.3048)
			(end 0.67945 -0.3048)
			(stroke
				(width 0.1)
				(type default)
			)
			(layer "F.Fab")
		)
		(fp_line
			(start 0.12065 -0.2794)
			(end 0.12065 -0.3048)
			(stroke
				(width 0.1)
				(type default)
			)
			(layer "F.Fab")
		)
		(fp_line
			(start -0.12065 -0.2794)
			(end 0.12065 -0.2794)
			(stroke
				(width 0.1)
				(type default)
			)
			(layer "F.Fab")
		)
		(fp_line
			(start 0.120396 0.2794)
			(end -0.12065 0.2794)
			(stroke
				(width 0.1)
				(type default)
			)
			(layer "F.Fab")
		)
		(fp_line
			(start -0.12065 0.2794)
			(end -0.12065 0.3048)
			(stroke
				(width 0.1)
				(type default)
			)
			(layer "F.Fab")
		)
		(fp_line
			(start 0.67945 0.3048)
			(end 0.120396 0.3048)
			(stroke
				(width 0.1)
				(type default)
			)
			(layer "F.Fab")
		)
		(fp_line
			(start 0.120396 0.3048)
			(end 0.120396 0.2794)
			(stroke
				(width 0.1)
				(type default)
			)
			(layer "F.Fab")
		)
		(fp_line
			(start -0.12065 0.3048)
			(end -0.67945 0.3048)
			(stroke
				(width 0.1)
				(type default)
			)
			(layer "F.Fab")
		)
		(fp_line
			(start -0.67945 0.3048)
			(end -0.67945 -0.305054)
			(stroke
				(width 0.1)
				(type default)
			)
			(layer "F.Fab")
		)
		(pad "1" smd circle
			(at -0.40005 0 90)
			(size 0 0)
			(layers "F.Cu" "F.Mask" "F.Paste")
			(net "CPU0_XTRIG_L7")
		)
		(pad "2" smd circle
			(at 0.40005 0 90)
			(size 0 0)
			(layers "F.Cu" "F.Mask" "F.Paste")
			(net "FM_CPU0_XTRIG_L7")
		)
	)
	(footprint ""
		(layer "F.Cu")
		(at 251.474224 -133.622796)
		(property "Reference" "R1655"
			(at 0 0 0)
			(layer "F.SilkS")
			(hide yes)
			(effects
				(font
					(size 1.27 1.27)
				)
			)
		)
		(property "Value" ""
			(at 0 0 0)
			(layer "F.Fab")
			(effects
				(font
					(size 1.27 1.27)
				)
			)
		)
		(duplicate_pad_numbers_are_jumpers no)
		(fp_line
			(start -0.7874 -0.4064)
			(end 0.7874 -0.4064)
			(stroke
				(width 0.1524)
				(type default)
			)
			(layer "F.SilkS")
		)
		(fp_line
			(start -0.7874 0.4064)
			(end -0.7874 -0.4064)
			(stroke
				(width 0.1524)
				(type default)
			)
			(layer "F.SilkS")
		)
		(fp_line
			(start 0.7874 -0.4064)
			(end 0.7874 0.4064)
			(stroke
				(width 0.1524)
				(type default)
			)
			(layer "F.SilkS")
		)
		(fp_line
			(start 0.7874 0.4064)
			(end -0.7874 0.4064)
			(stroke
				(width 0.1524)
				(type default)
			)
			(layer "F.SilkS")
		)
		(fp_line
			(start -0.67945 -0.305054)
			(end -0.12065 -0.305054)
			(stroke
				(width 0.1)
				(type default)
			)
			(layer "F.Fab")
		)
		(fp_line
			(start -0.67945 0.3048)
			(end -0.67945 -0.305054)
			(stroke
				(width 0.1)
				(type default)
			)
			(layer "F.Fab")
		)
		(fp_line
			(start -0.12065 -0.305054)
			(end -0.12065 -0.2794)
			(stroke
				(width 0.1)
				(type default)
			)
			(layer "F.Fab")
		)
		(fp_line
			(start -0.12065 -0.2794)
			(end 0.12065 -0.2794)
			(stroke
				(width 0.1)
				(type default)
			)
			(layer "F.Fab")
		)
		(fp_line
			(start -0.12065 0.2794)
			(end -0.12065 0.3048)
			(stroke
				(width 0.1)
				(type default)
			)
			(layer "F.Fab")
		)
		(fp_line
			(start -0.12065 0.3048)
			(end -0.67945 0.3048)
			(stroke
				(width 0.1)
				(type default)
			)
			(layer "F.Fab")
		)
		(fp_line
			(start 0.120396 0.2794)
			(end -0.12065 0.2794)
			(stroke
				(width 0.1)
				(type default)
			)
			(layer "F.Fab")
		)
		(fp_line
			(start 0.120396 0.3048)
			(end 0.120396 0.2794)
			(stroke
				(width 0.1)
				(type default)
			)
			(layer "F.Fab")
		)
		(fp_line
			(start 0.12065 -0.3048)
			(end 0.67945 -0.3048)
			(stroke
				(width 0.1)
				(type default)
			)
			(layer "F.Fab")
		)
		(fp_line
			(start 0.12065 -0.2794)
			(end 0.12065 -0.3048)
			(stroke
				(width 0.1)
				(type default)
			)
			(layer "F.Fab")
		)
		(fp_line
			(start 0.67945 -0.3048)
			(end 0.67945 0.3048)
			(stroke
				(width 0.1)
				(type default)
			)
			(layer "F.Fab")
		)
		(fp_line
			(start 0.67945 0.3048)
			(end 0.120396 0.3048)
			(stroke
				(width 0.1)
				(type default)
			)
			(layer "F.Fab")
		)
		(pad "1" smd circle
			(at -0.40005 0)
			(size 0 0)
			(layers "F.Cu" "F.Mask" "F.Paste")
			(net "P3V3_AUX")
		)
		(pad "2" smd circle
			(at 0.40005 0)
			(size 0 0)
			(layers "F.Cu" "F.Mask" "F.Paste")
			(net "SPI_CPU0_LVC3_SCM_CS1_N")
		)
	)
	(footprint ""
		(layer "F.Cu")
		(at 376.174 -427.482 90)
		(property "Reference" "C1070"
			(at 0 0 90)
			(layer "F.SilkS")
			(hide yes)
			(effects
				(font
					(size 1.27 1.27)
				)
			)
		)
		(property "Value" ""
			(at 0 0 90)
			(layer "F.Fab")
			(effects
				(font
					(size 1.27 1.27)
				)
			)
		)
		(duplicate_pad_numbers_are_jumpers no)
		(fp_line
			(start 0.299974 -0.150114)
			(end 0.299974 0.150114)
			(stroke
				(width 0.1)
				(type default)
			)
			(layer "F.Fab")
		)
		(fp_line
			(start -0.299974 -0.150114)
			(end 0.299974 -0.150114)
			(stroke
				(width 0.1)
				(type default)
			)
			(layer "F.Fab")
		)
		(fp_line
			(start 0.299974 0.150114)
			(end -0.299974 0.150114)
			(stroke
				(width 0.1)
				(type default)
			)
			(layer "F.Fab")
		)
		(fp_line
			(start -0.299974 0.150114)
			(end -0.299974 -0.150114)
			(stroke
				(width 0.1)
				(type default)
			)
			(layer "F.Fab")
		)
		(pad "1" smd rect
			(at -0.2667 0 90)
			(size 0.3048 0.381)
			(layers "F.Cu" "F.Mask" "F.Paste")
			(net "P3V3_AUX")
		)
		(pad "2" smd rect
			(at 0.2667 0 90)
			(size 0.3048 0.381)
			(layers "F.Cu" "F.Mask" "F.Paste")
			(net "GND")
		)
	)
)
